# T6G (Grand Teton) — schematic netlist excerpt (pin names and nets, part order shuffled) for the footprints in the layout excerpt that follows; sources: Cadence DE-HDL packaged netlist, KiCad conversion of 04192023_DAF0TMB3IC0_F0TG_MB_C_brd_V02_OCP.brd

PC488_2  Q_CAP  22UF 16V 20% X6S  pkg C0805  page 194 : A = SW_P12V_AUX_PVDDCR_CPU0_P0_FLT ; B = GND
R2999  Q_RES  2.2K 5% EMPTY  pkg 0402LF  page 151 : A = SMB_2_BMC_GPU_SCL ; B = P3V3_AUX
C637  Q_CAP  100UF 4V 20% X6S  pkg C0805  page 290 : A = P0V9_CPU0_RT1_2A ; B = GND
C190  Q_CAP  1UF 4V 20% X6S  pkg 0201  page 323 : A = P0V9_CPU1_RT0_2A ; B = GND

(kicad_pcb
	(version 20260206)
	(generator "pcbnew")
	(generator_version "10.0")
	(general
		(thickness 1.6)
		(legacy_teardrops no)
	)
	(paper "A4")
	(title_block
		(title "04192023_DAF0TMB3IC0_F0TG_MB_C_brd_V02_OCP.brd")
		(comment 1 "Grand Teton / footprints 4977-4980 of 8354")
	)
	(layers
		(0 "F.Cu" signal "TOP")
		(4 "In1.Cu" signal "GND")
		(6 "In2.Cu" signal "IN1")
		(8 "In3.Cu" signal "GND1")
		(10 "In4.Cu" signal "IN2")
		(12 "In5.Cu" signal "GND2")
		(14 "In6.Cu" signal "IN3")
		(16 "In7.Cu" signal "GND3")
		(18 "In8.Cu" signal "VCC")
		(20 "In9.Cu" signal "VCC1")
		(22 "In10.Cu" signal "GND4")
		(24 "In11.Cu" signal "IN4")
		(26 "In12.Cu" signal "GND5")
		(28 "In13.Cu" signal "IN5")
		(30 "In14.Cu" signal "GND6")
		(32 "In15.Cu" signal "IN6")
		(34 "In16.Cu" signal "GND7")
		(2 "B.Cu" signal "BOTTOM")
		(9 "F.Adhes" user "F.Adhesive")
		(11 "B.Adhes" user "B.Adhesive")
		(13 "F.Paste" user "Package Geometry/Pastemask Top")
		(15 "B.Paste" user "Package Geometry/Pastemask Bottom")
		(5 "F.SilkS" user "Ref Des/Silkscreen Top")
		(7 "B.SilkS" user "Ref Des/Silkscreen Bottom")
		(1 "F.Mask" user "Board Geometry/Soldermask Top")
		(3 "B.Mask" user "Board Geometry/Soldermask Bottom")
		(17 "Dwgs.User" user "User.Drawings")
		(19 "Cmts.User" user "User.Comments")
		(21 "Eco1.User" user "User.Eco1")
		(23 "Eco2.User" user "User.Eco2")
		(25 "Edge.Cuts" user "Board Geometry/Outline")
		(27 "Margin" user)
		(31 "F.CrtYd" user "Package Geometry/Place Bound Top")
		(29 "B.CrtYd" user "Package Geometry/Place Bound Bottom")
		(35 "F.Fab" user "Ref Des/Assembly Top")
		(33 "B.Fab" user "Ref Des/Assembly Bottom")
	)
	(footprint ""
		(layer "B.Cu")
		(at 330.94041 -397.228568)
		(property "Reference" "C637"
			(at 0 0 0)
			(layer "B.SilkS")
			(hide yes)
			(effects
				(font
					(size 1.27 1.27)
				)
				(justify mirror)
			)
		)
		(property "Value" ""
			(at 0 0 0)
			(layer "B.Fab")
			(effects
				(font
					(size 1.27 1.27)
				)
				(justify mirror)
			)
		)
		(duplicate_pad_numbers_are_jumpers no)
		(fp_line
			(start -1.524 -0.762)
			(end -1.524 0.762)
			(stroke
				(width 0.1524)
				(type default)
			)
			(layer "B.SilkS")
		)
		(fp_line
			(start -1.524 0.762)
			(end 1.524 0.762)
			(stroke
				(width 0.1524)
				(type default)
			)
			(layer "B.SilkS")
		)
		(fp_line
			(start 1.524 -0.762)
			(end -1.524 -0.762)
			(stroke
				(width 0.1524)
				(type default)
			)
			(layer "B.SilkS")
		)
		(fp_line
			(start 1.524 0.762)
			(end 1.524 -0.762)
			(stroke
				(width 0.1524)
				(type default)
			)
			(layer "B.SilkS")
		)
		(fp_line
			(start -1.1049 -0.724916)
			(end 1.1049 -0.724916)
			(stroke
				(width 0.1)
				(type default)
			)
			(layer "B.Fab")
		)
		(fp_line
			(start -1.1049 0.724916)
			(end -1.1049 -0.724916)
			(stroke
				(width 0.1)
				(type default)
			)
			(layer "B.Fab")
		)
		(fp_line
			(start 1.1049 -0.724916)
			(end 1.1049 0.724916)
			(stroke
				(width 0.1)
				(type default)
			)
			(layer "B.Fab")
		)
		(fp_line
			(start 1.1049 0.724916)
			(end -1.1049 0.724916)
			(stroke
				(width 0.1)
				(type default)
			)
			(layer "B.Fab")
		)
		(pad "1" smd rect
			(at 0.889 0)
			(size 1.016 1.27)
			(layers "B.Cu" "B.Mask" "B.Paste")
			(net "P0V9_CPU0_RT1_2A")
		)
		(pad "2" smd rect
			(at -0.889 0)
			(size 1.016 1.27)
			(layers "B.Cu" "B.Mask" "B.Paste")
			(net "GND")
		)
	)
	(footprint ""
		(layer "B.Cu")
		(at 371.553486 -182.676038 -90)
		(property "Reference" "PC488_2"
			(at 0 0 90)
			(layer "B.SilkS")
			(hide yes)
			(effects
				(font
					(size 1.27 1.27)
				)
				(justify mirror)
			)
		)
		(property "Value" ""
			(at 0 0 90)
			(layer "B.Fab")
			(effects
				(font
					(size 1.27 1.27)
				)
				(justify mirror)
			)
		)
		(duplicate_pad_numbers_are_jumpers no)
		(fp_line
			(start -1.524 0.762)
			(end 1.524 0.762)
			(stroke
				(width 0.1524)
				(type default)
			)
			(layer "B.SilkS")
		)
		(fp_line
			(start 1.524 0.762)
			(end 1.524 -0.762)
			(stroke
				(width 0.1524)
				(type default)
			)
			(layer "B.SilkS")
		)
		(fp_line
			(start -1.524 -0.762)
			(end -1.524 0.762)
			(stroke
				(width 0.1524)
				(type default)
			)
			(layer "B.SilkS")
		)
		(fp_line
			(start 1.524 -0.762)
			(end -1.524 -0.762)
			(stroke
				(width 0.1524)
				(type default)
			)
			(layer "B.SilkS")
		)
		(fp_line
			(start -1.1049 0.724916)
			(end -1.1049 -0.724916)
			(stroke
				(width 0.1)
				(type default)
			)
			(layer "B.Fab")
		)
		(fp_line
			(start 1.1049 0.724916)
			(end -1.1049 0.724916)
			(stroke
				(width 0.1)
				(type default)
			)
			(layer "B.Fab")
		)
		(fp_line
			(start -1.1049 -0.724916)
			(end 1.1049 -0.724916)
			(stroke
				(width 0.1)
				(type default)
			)
			(layer "B.Fab")
		)
		(fp_line
			(start 1.1049 -0.724916)
			(end 1.1049 0.724916)
			(stroke
				(width 0.1)
				(type default)
			)
			(layer "B.Fab")
		)
		(pad "1" smd rect
			(at 0.889 0 270)
			(size 1.016 1.27)
			(layers "B.Cu" "B.Mask" "B.Paste")
			(net "SW_P12V_AUX_PVDDCR_CPU0_P0_FLT")
		)
		(pad "2" smd rect
			(at -0.889 0 270)
			(size 1.016 1.27)
			(layers "B.Cu" "B.Mask" "B.Paste")
			(net "GND")
		)
	)
	(footprint ""
		(layer "B.Cu")
		(at 156.67101 -16.851122 -90)
		(property "Reference" "R2999"
			(at 0 0 90)
			(layer "B.SilkS")
			(hide yes)
			(effects
				(font
					(size 1.27 1.27)
				)
				(justify mirror)
			)
		)
		(property "Value" ""
			(at 0 0 90)
			(layer "B.Fab")
			(effects
				(font
					(size 1.27 1.27)
				)
				(justify mirror)
			)
		)
		(duplicate_pad_numbers_are_jumpers no)
		(fp_line
			(start -0.7874 0.4064)
			(end 0.7874 0.4064)
			(stroke
				(width 0.1524)
				(type default)
			)
			(layer "B.SilkS")
		)
		(fp_line
			(start 0.7874 0.4064)
			(end 0.7874 -0.4064)
			(stroke
				(width 0.1524)
				(type default)
			)
			(layer "B.SilkS")
		)
		(fp_line
			(start -0.7874 -0.4064)
			(end -0.7874 0.4064)
			(stroke
				(width 0.1524)
				(type default)
			)
			(layer "B.SilkS")
		)
		(fp_line
			(start 0.7874 -0.4064)
			(end -0.7874 -0.4064)
			(stroke
				(width 0.1524)
				(type default)
			)
			(layer "B.SilkS")
		)
		(fp_line
			(start -0.67945 0.3048)
			(end -0.120396 0.3048)
			(stroke
				(width 0.1)
				(type default)
			)
			(layer "B.Fab")
		)
		(fp_line
			(start -0.120396 0.3048)
			(end -0.120396 0.2794)
			(stroke
				(width 0.1)
				(type default)
			)
			(layer "B.Fab")
		)
		(fp_line
			(start 0.12065 0.3048)
			(end 0.67945 0.3048)
			(stroke
				(width 0.1)
				(type default)
			)
			(layer "B.Fab")
		)
		(fp_line
			(start 0.67945 0.3048)
			(end 0.67945 -0.305054)
			(stroke
				(width 0.1)
				(type default)
			)
			(layer "B.Fab")
		)
		(fp_line
			(start -0.120396 0.2794)
			(end 0.12065 0.2794)
			(stroke
				(width 0.1)
				(type default)
			)
			(layer "B.Fab")
		)
		(fp_line
			(start 0.12065 0.2794)
			(end 0.12065 0.3048)
			(stroke
				(width 0.1)
				(type default)
			)
			(layer "B.Fab")
		)
		(fp_line
			(start -0.12065 -0.2794)
			(end -0.12065 -0.3048)
			(stroke
				(width 0.1)
				(type default)
			)
			(layer "B.Fab")
		)
		(fp_line
			(start 0.12065 -0.2794)
			(end -0.12065 -0.2794)
			(stroke
				(width 0.1)
				(type default)
			)
			(layer "B.Fab")
		)
		(fp_line
			(start -0.67945 -0.3048)
			(end -0.67945 0.3048)
			(stroke
				(width 0.1)
				(type default)
			)
			(layer "B.Fab")
		)
		(fp_line
			(start -0.12065 -0.3048)
			(end -0.67945 -0.3048)
			(stroke
				(width 0.1)
				(type default)
			)
			(layer "B.Fab")
		)
		(fp_line
			(start 0.12065 -0.305054)
			(end 0.12065 -0.2794)
			(stroke
				(width 0.1)
				(type default)
			)
			(layer "B.Fab")
		)
		(fp_line
			(start 0.67945 -0.305054)
			(end 0.12065 -0.305054)
			(stroke
				(width 0.1)
				(type default)
			)
			(layer "B.Fab")
		)
		(pad "1" smd circle
			(at 0.40005 0 90)
			(size 0 0)
			(layers "B.Cu" "B.Mask" "B.Paste")
			(net "SMB_2_BMC_GPU_SCL")
		)
		(pad "2" smd circle
			(at -0.40005 0 90)
			(size 0 0)
			(layers "B.Cu" "B.Mask" "B.Paste")
			(net "P3V3_AUX")
		)
	)
	(footprint ""
		(layer "B.Cu")
		(at 61.778642 -386.766562 90)
		(property "Reference" "C190"
			(at 0 0 90)
			(layer "B.SilkS")
			(hide yes)
			(effects
				(font
					(size 1.27 1.27)
				)
				(justify mirror)
			)
		)
		(property "Value" ""
			(at 0 0 90)
			(layer "B.Fab")
			(effects
				(font
					(size 1.27 1.27)
				)
				(justify mirror)
			)
		)
		(duplicate_pad_numbers_are_jumpers no)
		(fp_line
			(start 0.299974 -0.150114)
			(end -0.299974 -0.150114)
			(stroke
				(width 0.1)
				(type default)
			)
			(layer "B.Fab")
		)
		(fp_line
			(start -0.299974 -0.150114)
			(end -0.299974 0.150114)
			(stroke
				(width 0.1)
				(type default)
			)
			(layer "B.Fab")
		)
		(fp_line
			(start 0.299974 0.150114)
			(end 0.299974 -0.150114)
			(stroke
				(width 0.1)
				(type default)
			)
			(layer "B.Fab")
		)
		(fp_line
			(start -0.299974 0.150114)
			(end 0.299974 0.150114)
			(stroke
				(width 0.1)
				(type default)
			)
			(layer "B.Fab")
		)
		(pad "1" smd rect
			(at 0.2667 0 270)
			(size 0.3048 0.381)
			(layers "B.Cu" "B.Mask" "B.Paste")
			(net "P0V9_CPU1_RT0_2A")
		)
		(pad "2" smd rect
			(at -0.2667 0 270)
			(size 0.3048 0.381)
			(layers "B.Cu" "B.Mask" "B.Paste")
			(net "GND")
		)
	)
)
